# T6G (Grand Teton) — schematic netlist excerpt (pin names and nets, part order shuffled) for the footprints in the layout excerpt that follows; sources: Cadence DE-HDL packaged netlist, KiCad conversion of 04192023_DAF0TMB3IC0_F0TG_MB_C_brd_V02_OCP.brd

R8015  Q_RES  0 5% EMPTY  pkg 0402LF  page 143 : A = OCP_V3_2_PRSNT01_R_N ; B = OCP_V3_2_PRSNT01_R1_N
PR4008  Q_RES  1.33K 1% CHIP  pkg 0402LF  page 152 : A = P12V_SCM_SENSE ; B = GND
R6716  Q_RES  1K 1% EMPTY  pkg 0201LF  page 320 : A = P1V8_CPU1_RT_1D ; B = RT_CPU1_P0_ADDR1

(kicad_pcb
	(version 20260206)
	(generator "pcbnew")
	(generator_version "10.0")
	(general
		(thickness 1.6)
		(legacy_teardrops no)
	)
	(paper "A4")
	(title_block
		(title "04192023_DAF0TMB3IC0_F0TG_MB_C_brd_V02_OCP.brd")
		(comment 1 "Grand Teton / footprints 1847-1849 of 8354")
	)
	(layers
		(0 "F.Cu" signal "TOP")
		(4 "In1.Cu" signal "GND")
		(6 "In2.Cu" signal "IN1")
		(8 "In3.Cu" signal "GND1")
		(10 "In4.Cu" signal "IN2")
		(12 "In5.Cu" signal "GND2")
		(14 "In6.Cu" signal "IN3")
		(16 "In7.Cu" signal "GND3")
		(18 "In8.Cu" signal "VCC")
		(20 "In9.Cu" signal "VCC1")
		(22 "In10.Cu" signal "GND4")
		(24 "In11.Cu" signal "IN4")
		(26 "In12.Cu" signal "GND5")
		(28 "In13.Cu" signal "IN5")
		(30 "In14.Cu" signal "GND6")
		(32 "In15.Cu" signal "IN6")
		(34 "In16.Cu" signal "GND7")
		(2 "B.Cu" signal "BOTTOM")
		(9 "F.Adhes" user "F.Adhesive")
		(11 "B.Adhes" user "B.Adhesive")
		(13 "F.Paste" user "Package Geometry/Pastemask Top")
		(15 "B.Paste" user "Package Geometry/Pastemask Bottom")
		(5 "F.SilkS" user "Ref Des/Silkscreen Top")
		(7 "B.SilkS" user "Ref Des/Silkscreen Bottom")
		(1 "F.Mask" user "Board Geometry/Soldermask Top")
		(3 "B.Mask" user "Board Geometry/Soldermask Bottom")
		(17 "Dwgs.User" user "User.Drawings")
		(19 "Cmts.User" user "User.Comments")
		(21 "Eco1.User" user "User.Eco1")
		(23 "Eco2.User" user "User.Eco2")
		(25 "Edge.Cuts" user "Board Geometry/Outline")
		(27 "Margin" user)
		(31 "F.CrtYd" user "Package Geometry/Place Bound Top")
		(29 "B.CrtYd" user "Package Geometry/Place Bound Bottom")
		(35 "F.Fab" user "Ref Des/Assembly Top")
		(33 "B.Fab" user "Ref Des/Assembly Bottom")
	)
	(footprint ""
		(layer "F.Cu")
		(at 9.271 -73.279)
		(property "Reference" "R8015"
			(at 0 0 0)
			(layer "F.SilkS")
			(hide yes)
			(effects
				(font
					(size 1.27 1.27)
				)
			)
		)
		(property "Value" ""
			(at 0 0 0)
			(layer "F.Fab")
			(effects
				(font
					(size 1.27 1.27)
				)
			)
		)
		(duplicate_pad_numbers_are_jumpers no)
		(fp_line
			(start -0.7874 -0.4064)
			(end 0.7874 -0.4064)
			(stroke
				(width 0.1524)
				(type default)
			)
			(layer "F.SilkS")
		)
		(fp_line
			(start -0.7874 0.4064)
			(end -0.7874 -0.4064)
			(stroke
				(width 0.1524)
				(type default)
			)
			(layer "F.SilkS")
		)
		(fp_line
			(start 0.7874 -0.4064)
			(end 0.7874 0.4064)
			(stroke
				(width 0.1524)
				(type default)
			)
			(layer "F.SilkS")
		)
		(fp_line
			(start 0.7874 0.4064)
			(end -0.7874 0.4064)
			(stroke
				(width 0.1524)
				(type default)
			)
			(layer "F.SilkS")
		)
		(fp_line
			(start -0.67945 -0.305054)
			(end -0.12065 -0.305054)
			(stroke
				(width 0.1)
				(type default)
			)
			(layer "F.Fab")
		)
		(fp_line
			(start -0.67945 0.3048)
			(end -0.67945 -0.305054)
			(stroke
				(width 0.1)
				(type default)
			)
			(layer "F.Fab")
		)
		(fp_line
			(start -0.12065 -0.305054)
			(end -0.12065 -0.2794)
			(stroke
				(width 0.1)
				(type default)
			)
			(layer "F.Fab")
		)
		(fp_line
			(start -0.12065 -0.2794)
			(end 0.12065 -0.2794)
			(stroke
				(width 0.1)
				(type default)
			)
			(layer "F.Fab")
		)
		(fp_line
			(start -0.12065 0.2794)
			(end -0.12065 0.3048)
			(stroke
				(width 0.1)
				(type default)
			)
			(layer "F.Fab")
		)
		(fp_line
			(start -0.12065 0.3048)
			(end -0.67945 0.3048)
			(stroke
				(width 0.1)
				(type default)
			)
			(layer "F.Fab")
		)
		(fp_line
			(start 0.120396 0.2794)
			(end -0.12065 0.2794)
			(stroke
				(width 0.1)
				(type default)
			)
			(layer "F.Fab")
		)
		(fp_line
			(start 0.120396 0.3048)
			(end 0.120396 0.2794)
			(stroke
				(width 0.1)
				(type default)
			)
			(layer "F.Fab")
		)
		(fp_line
			(start 0.12065 -0.3048)
			(end 0.67945 -0.3048)
			(stroke
				(width 0.1)
				(type default)
			)
			(layer "F.Fab")
		)
		(fp_line
			(start 0.12065 -0.2794)
			(end 0.12065 -0.3048)
			(stroke
				(width 0.1)
				(type default)
			)
			(layer "F.Fab")
		)
		(fp_line
			(start 0.67945 -0.3048)
			(end 0.67945 0.3048)
			(stroke
				(width 0.1)
				(type default)
			)
			(layer "F.Fab")
		)
		(fp_line
			(start 0.67945 0.3048)
			(end 0.120396 0.3048)
			(stroke
				(width 0.1)
				(type default)
			)
			(layer "F.Fab")
		)
		(pad "1" smd circle
			(at -0.40005 0)
			(size 0 0)
			(layers "F.Cu" "F.Mask" "F.Paste")
			(net "OCP_V3_2_PRSNT01_R_N")
		)
		(pad "2" smd circle
			(at 0.40005 0)
			(size 0 0)
			(layers "F.Cu" "F.Mask" "F.Paste")
			(net "OCP_V3_2_PRSNT01_R1_N")
		)
	)
	(footprint ""
		(layer "F.Cu")
		(at 185.928762 -26.788872 180)
		(property "Reference" "PR4008"
			(at 0 0 180)
			(layer "F.SilkS")
			(hide yes)
			(effects
				(font
					(size 1.27 1.27)
				)
			)
		)
		(property "Value" ""
			(at 0 0 180)
			(layer "F.Fab")
			(effects
				(font
					(size 1.27 1.27)
				)
			)
		)
		(duplicate_pad_numbers_are_jumpers no)
		(fp_line
			(start 0.7874 0.4064)
			(end -0.7874 0.4064)
			(stroke
				(width 0.1524)
				(type default)
			)
			(layer "F.SilkS")
		)
		(fp_line
			(start 0.7874 -0.4064)
			(end 0.7874 0.4064)
			(stroke
				(width 0.1524)
				(type default)
			)
			(layer "F.SilkS")
		)
		(fp_line
			(start -0.7874 0.4064)
			(end -0.7874 -0.4064)
			(stroke
				(width 0.1524)
				(type default)
			)
			(layer "F.SilkS")
		)
		(fp_line
			(start -0.7874 -0.4064)
			(end 0.7874 -0.4064)
			(stroke
				(width 0.1524)
				(type default)
			)
			(layer "F.SilkS")
		)
		(fp_line
			(start 0.67945 0.3048)
			(end 0.120396 0.3048)
			(stroke
				(width 0.1)
				(type default)
			)
			(layer "F.Fab")
		)
		(fp_line
			(start 0.67945 -0.3048)
			(end 0.67945 0.3048)
			(stroke
				(width 0.1)
				(type default)
			)
			(layer "F.Fab")
		)
		(fp_line
			(start 0.12065 -0.2794)
			(end 0.12065 -0.3048)
			(stroke
				(width 0.1)
				(type default)
			)
			(layer "F.Fab")
		)
		(fp_line
			(start 0.12065 -0.3048)
			(end 0.67945 -0.3048)
			(stroke
				(width 0.1)
				(type default)
			)
			(layer "F.Fab")
		)
		(fp_line
			(start 0.120396 0.3048)
			(end 0.120396 0.2794)
			(stroke
				(width 0.1)
				(type default)
			)
			(layer "F.Fab")
		)
		(fp_line
			(start 0.120396 0.2794)
			(end -0.12065 0.2794)
			(stroke
				(width 0.1)
				(type default)
			)
			(layer "F.Fab")
		)
		(fp_line
			(start -0.12065 0.3048)
			(end -0.67945 0.3048)
			(stroke
				(width 0.1)
				(type default)
			)
			(layer "F.Fab")
		)
		(fp_line
			(start -0.12065 0.2794)
			(end -0.12065 0.3048)
			(stroke
				(width 0.1)
				(type default)
			)
			(layer "F.Fab")
		)
		(fp_line
			(start -0.12065 -0.2794)
			(end 0.12065 -0.2794)
			(stroke
				(width 0.1)
				(type default)
			)
			(layer "F.Fab")
		)
		(fp_line
			(start -0.12065 -0.305054)
			(end -0.12065 -0.2794)
			(stroke
				(width 0.1)
				(type default)
			)
			(layer "F.Fab")
		)
		(fp_line
			(start -0.67945 0.3048)
			(end -0.67945 -0.305054)
			(stroke
				(width 0.1)
				(type default)
			)
			(layer "F.Fab")
		)
		(fp_line
			(start -0.67945 -0.305054)
			(end -0.12065 -0.305054)
			(stroke
				(width 0.1)
				(type default)
			)
			(layer "F.Fab")
		)
		(pad "1" smd circle
			(at -0.40005 0 180)
			(size 0 0)
			(layers "F.Cu" "F.Mask" "F.Paste")
			(net "P12V_SCM_SENSE")
		)
		(pad "2" smd circle
			(at 0.40005 0 180)
			(size 0 0)
			(layers "F.Cu" "F.Mask" "F.Paste")
			(net "GND")
		)
	)
	(footprint ""
		(layer "F.Cu")
		(at 70.9676 -382.6764 180)
		(property "Reference" "R6716"
			(at 0 0 180)
			(layer "F.SilkS")
			(hide yes)
			(effects
				(font
					(size 1.27 1.27)
				)
			)
		)
		(property "Value" ""
			(at 0 0 180)
			(layer "F.Fab")
			(effects
				(font
					(size 1.27 1.27)
				)
			)
		)
		(duplicate_pad_numbers_are_jumpers no)
		(fp_line
			(start 0.32512 0.175006)
			(end -0.32512 0.175006)
			(stroke
				(width 0.1)
				(type default)
			)
			(layer "F.Fab")
		)
		(fp_line
			(start 0.32512 -0.175006)
			(end 0.32512 0.175006)
			(stroke
				(width 0.1)
				(type default)
			)
			(layer "F.Fab")
		)
		(fp_line
			(start -0.32512 0.175006)
			(end -0.32512 -0.175006)
			(stroke
				(width 0.1)
				(type default)
			)
			(layer "F.Fab")
		)
		(fp_line
			(start -0.32512 -0.175006)
			(end 0.32512 -0.175006)
			(stroke
				(width 0.1)
				(type default)
			)
			(layer "F.Fab")
		)
		(pad "1" smd rect
			(at -0.2667 0 180)
			(size 0.3048 0.381)
			(layers "F.Cu" "F.Mask" "F.Paste")
			(net "P1V8_CPU1_RT_1D")
		)
		(pad "2" smd rect
			(at 0.2667 0)
			(size 0.3048 0.381)
			(layers "F.Cu" "F.Mask" "F.Paste")
			(net "RT_CPU1_P0_ADDR1")
		)
	)
)
